# S9S_MB_2U (Grand Teton) — schematic netlist excerpt (pin names and nets, part order shuffled) for the footprints in the layout excerpt that follows; sources: Cadence DE-HDL packaged netlist, KiCad conversion of 03242023_DA0F0TMBIJ0_F0T_Motherboard_J_brd_V01_OCP.brd

U175  LTC4307CMS8  IC  pkg MSOP8  page 234
  ENABLE  = SMB_BMC_SWB_EN_R
  SCL_OUT  = SMB_BMC_SWB_BUF_R_SCL
  SCL_IN  = SMB_BMC_SWB_R_SCL
  GND  = GND
  READY  = NC
  SDA_IN  = SMB_BMC_SWB_R_SDA
  SDA_OUT  = SMB_BMC_SWB_BUF_R_SDA
  VCC  = P3V3_AUX

PC476  Q_CAP  100NF 50V 10% EMPTY  pkg C0402  page 292 : A = PVCCINFAON_CPU1_VCC ; B = GND

(kicad_pcb
	(version 20260206)
	(generator "pcbnew")
	(generator_version "10.0")
	(general
		(thickness 1.6)
		(legacy_teardrops no)
	)
	(paper "A4")
	(title_block
		(title "03242023_DA0F0TMBIJ0_F0T_Motherboard_J_brd_V01_OCP.brd")
		(comment 1 "Grand Teton / footprints 3548-3549 of 6105")
	)
	(layers
		(0 "F.Cu" signal "TOP")
		(4 "In1.Cu" signal "GND")
		(6 "In2.Cu" signal "IN1")
		(8 "In3.Cu" signal "GND1")
		(10 "In4.Cu" signal "IN2")
		(12 "In5.Cu" signal "GND2")
		(14 "In6.Cu" signal "IN3")
		(16 "In7.Cu" signal "GND3")
		(18 "In8.Cu" signal "VCC")
		(20 "In9.Cu" signal "VCC1")
		(22 "In10.Cu" signal "GND4")
		(24 "In11.Cu" signal "IN4")
		(26 "In12.Cu" signal "GND5")
		(28 "In13.Cu" signal "IN5")
		(30 "In14.Cu" signal "GND6")
		(32 "In15.Cu" signal "IN6")
		(34 "In16.Cu" signal "GND7")
		(2 "B.Cu" signal "BOTTOM")
		(9 "F.Adhes" user "F.Adhesive")
		(11 "B.Adhes" user "B.Adhesive")
		(13 "F.Paste" user "Package Geometry/Pastemask Top")
		(15 "B.Paste" user "Package Geometry/Pastemask Bottom")
		(5 "F.SilkS" user "Ref Des/Silkscreen Top")
		(7 "B.SilkS" user "Ref Des/Silkscreen Bottom")
		(1 "F.Mask" user "Board Geometry/Soldermask Top")
		(3 "B.Mask" user "Board Geometry/Soldermask Bottom")
		(17 "Dwgs.User" user "User.Drawings")
		(19 "Cmts.User" user "User.Comments")
		(21 "Eco1.User" user "User.Eco1")
		(23 "Eco2.User" user "User.Eco2")
		(25 "Edge.Cuts" user "Board Geometry/Outline")
		(27 "Margin" user)
		(31 "F.CrtYd" user "Package Geometry/Place Bound Top")
		(29 "B.CrtYd" user "Package Geometry/Place Bound Bottom")
		(35 "F.Fab" user "Ref Des/Assembly Top")
		(33 "B.Fab" user "Ref Des/Assembly Bottom")
	)
	(footprint ""
		(layer "F.Cu")
		(at 163.88715 -425.245276 -90)
		(property "Reference" "U175"
			(at 1.581404 -2.540762 90)
			(unlocked yes)
			(layer "F.SilkS")
			(effects
				(font
					(size 0.7874 0.5842)
					(thickness 0.1524)
				)
				(justify left)
			)
		)
		(property "Value" ""
			(at 0 0 270)
			(layer "F.Fab")
			(effects
				(font
					(size 1.27 1.27)
				)
			)
		)
		(duplicate_pad_numbers_are_jumpers no)
		(fp_line
			(start -1.3716 1.524)
			(end -1.3716 -1.524)
			(stroke
				(width 0.1524)
				(type default)
			)
			(layer "F.SilkS")
		)
		(fp_line
			(start 1.3716 1.524)
			(end -1.3716 1.524)
			(stroke
				(width 0.1524)
				(type default)
			)
			(layer "F.SilkS")
		)
		(fp_line
			(start 0 -1.016)
			(end 0.508 -1.524)
			(stroke
				(width 0.1524)
				(type default)
			)
			(layer "F.SilkS")
		)
		(fp_line
			(start -1.3716 -1.524)
			(end -0.508 -1.524)
			(stroke
				(width 0.1524)
				(type default)
			)
			(layer "F.SilkS")
		)
		(fp_line
			(start -0.508 -1.524)
			(end 0 -1.016)
			(stroke
				(width 0.1524)
				(type default)
			)
			(layer "F.SilkS")
		)
		(fp_line
			(start 0.508 -1.524)
			(end 1.3716 -1.524)
			(stroke
				(width 0.1524)
				(type default)
			)
			(layer "F.SilkS")
		)
		(fp_line
			(start 1.3716 -1.524)
			(end 1.3716 1.524)
			(stroke
				(width 0.1524)
				(type default)
			)
			(layer "F.SilkS")
		)
		(fp_poly
			(pts
				(xy -3.60172 -1.344168) (xy -3.048 -1.016) (xy -3.60172 -0.719328)
			)
			(stroke
				(width 0)
				(type default)
			)
			(fill yes)
			(layer "F.SilkS")
		)
		(fp_line
			(start -1.5494 1.524)
			(end -1.5494 1.0668)
			(stroke
				(width 0.1)
				(type default)
			)
			(layer "F.Fab")
		)
		(fp_line
			(start 1.5494 1.524)
			(end -1.5494 1.524)
			(stroke
				(width 0.1)
				(type default)
			)
			(layer "F.Fab")
		)
		(fp_line
			(start -2.54 1.0668)
			(end -2.54 -1.0668)
			(stroke
				(width 0.1)
				(type default)
			)
			(layer "F.Fab")
		)
		(fp_line
			(start -1.5494 1.0668)
			(end -2.54 1.0668)
			(stroke
				(width 0.1)
				(type default)
			)
			(layer "F.Fab")
		)
		(fp_line
			(start -1.5494 1.0668)
			(end -1.5494 -1.0668)
			(stroke
				(width 0.1)
				(type default)
			)
			(layer "F.Fab")
		)
		(fp_line
			(start 1.5494 1.0668)
			(end 1.5494 1.524)
			(stroke
				(width 0.1)
				(type default)
			)
			(layer "F.Fab")
		)
		(fp_line
			(start 2.54 1.0668)
			(end 1.5494 1.0668)
			(stroke
				(width 0.1)
				(type default)
			)
			(layer "F.Fab")
		)
		(fp_line
			(start -2.54 -1.0668)
			(end -1.5494 -1.0668)
			(stroke
				(width 0.1)
				(type default)
			)
			(layer "F.Fab")
		)
		(fp_line
			(start -1.5494 -1.0668)
			(end -1.5494 -1.524)
			(stroke
				(width 0.1)
				(type default)
			)
			(layer "F.Fab")
		)
		(fp_line
			(start 1.5494 -1.0668)
			(end 1.5494 1.0668)
			(stroke
				(width 0.1)
				(type default)
			)
			(layer "F.Fab")
		)
		(fp_line
			(start 1.5494 -1.0668)
			(end 2.54 -1.0668)
			(stroke
				(width 0.1)
				(type default)
			)
			(layer "F.Fab")
		)
		(fp_line
			(start 2.54 -1.0668)
			(end 2.54 1.0668)
			(stroke
				(width 0.1)
				(type default)
			)
			(layer "F.Fab")
		)
		(fp_line
			(start -1.5494 -1.524)
			(end 1.5494 -1.524)
			(stroke
				(width 0.1)
				(type default)
			)
			(layer "F.Fab")
		)
		(fp_line
			(start 1.5494 -1.524)
			(end 1.5494 -1.0668)
			(stroke
				(width 0.1)
				(type default)
			)
			(layer "F.Fab")
		)
		(fp_poly
			(pts
				(xy -3.60172 -0.719328) (xy -3.60172 -1.344168) (xy -3.048 -1.016)
			)
			(stroke
				(width 0)
				(type default)
			)
			(fill yes)
			(layer "F.Fab")
		)
		(pad "1" smd rect
			(at -2.232406 -0.975106 180)
			(size 0.3556 1.4224)
			(layers "F.Cu" "F.Mask" "F.Paste")
			(net "SMB_BMC_SWB_EN_R")
		)
		(pad "2" smd rect
			(at -2.232406 -0.32512 180)
			(size 0.3556 1.4224)
			(layers "F.Cu" "F.Mask" "F.Paste")
			(net "SMB_BMC_SWB_BUF_R_SCL")
		)
		(pad "3" smd rect
			(at -2.232406 0.32512 180)
			(size 0.3556 1.4224)
			(layers "F.Cu" "F.Mask" "F.Paste")
			(net "SMB_BMC_SWB_R_SCL")
		)
		(pad "4" smd rect
			(at -2.232406 0.975106 180)
			(size 0.3556 1.4224)
			(layers "F.Cu" "F.Mask" "F.Paste")
			(net "GND")
		)
		(pad "5" smd rect
			(at 2.232406 0.975106 180)
			(size 0.3556 1.4224)
			(layers "F.Cu" "F.Mask" "F.Paste")
			(net "Net_1934")
		)
		(pad "6" smd rect
			(at 2.232406 0.32512 180)
			(size 0.3556 1.4224)
			(layers "F.Cu" "F.Mask" "F.Paste")
			(net "SMB_BMC_SWB_R_SDA")
		)
		(pad "7" smd rect
			(at 2.232406 -0.32512 180)
			(size 0.3556 1.4224)
			(layers "F.Cu" "F.Mask" "F.Paste")
			(net "SMB_BMC_SWB_BUF_R_SDA")
		)
		(pad "8" smd rect
			(at 2.232406 -0.975106 180)
			(size 0.3556 1.4224)
			(layers "F.Cu" "F.Mask" "F.Paste")
			(net "P3V3_AUX")
		)
	)
	(footprint ""
		(layer "F.Cu")
		(at 27.0383 -126.332996 180)
		(property "Reference" "PC476"
			(at 0 0 180)
			(layer "F.SilkS")
			(hide yes)
			(effects
				(font
					(size 1.27 1.27)
				)
			)
		)
		(property "Value" ""
			(at 0 0 180)
			(layer "F.Fab")
			(effects
				(font
					(size 1.27 1.27)
				)
			)
		)
		(duplicate_pad_numbers_are_jumpers no)
		(fp_line
			(start 0.7874 0.4064)
			(end -0.7874 0.4064)
			(stroke
				(width 0.1524)
				(type default)
			)
			(layer "F.SilkS")
		)
		(fp_line
			(start 0.7874 -0.4064)
			(end 0.7874 0.4064)
			(stroke
				(width 0.1524)
				(type default)
			)
			(layer "F.SilkS")
		)
		(fp_line
			(start -0.7874 0.4064)
			(end -0.7874 -0.4064)
			(stroke
				(width 0.1524)
				(type default)
			)
			(layer "F.SilkS")
		)
		(fp_line
			(start -0.7874 -0.4064)
			(end 0.7874 -0.4064)
			(stroke
				(width 0.1524)
				(type default)
			)
			(layer "F.SilkS")
		)
		(fp_line
			(start 0.67945 0.3048)
			(end 0.120396 0.3048)
			(stroke
				(width 0.1)
				(type default)
			)
			(layer "F.Fab")
		)
		(fp_line
			(start 0.67945 -0.3048)
			(end 0.67945 0.3048)
			(stroke
				(width 0.1)
				(type default)
			)
			(layer "F.Fab")
		)
		(fp_line
			(start 0.12065 -0.2794)
			(end 0.12065 -0.3048)
			(stroke
				(width 0.1)
				(type default)
			)
			(layer "F.Fab")
		)
		(fp_line
			(start 0.12065 -0.3048)
			(end 0.67945 -0.3048)
			(stroke
				(width 0.1)
				(type default)
			)
			(layer "F.Fab")
		)
		(fp_line
			(start 0.120396 0.3048)
			(end 0.120396 0.2794)
			(stroke
				(width 0.1)
				(type default)
			)
			(layer "F.Fab")
		)
		(fp_line
			(start 0.120396 0.2794)
			(end -0.12065 0.2794)
			(stroke
				(width 0.1)
				(type default)
			)
			(layer "F.Fab")
		)
		(fp_line
			(start -0.12065 0.3048)
			(end -0.67945 0.3048)
			(stroke
				(width 0.1)
				(type default)
			)
			(layer "F.Fab")
		)
		(fp_line
			(start -0.12065 0.2794)
			(end -0.12065 0.3048)
			(stroke
				(width 0.1)
				(type default)
			)
			(layer "F.Fab")
		)
		(fp_line
			(start -0.12065 -0.2794)
			(end 0.12065 -0.2794)
			(stroke
				(width 0.1)
				(type default)
			)
			(layer "F.Fab")
		)
		(fp_line
			(start -0.12065 -0.305054)
			(end -0.12065 -0.2794)
			(stroke
				(width 0.1)
				(type default)
			)
			(layer "F.Fab")
		)
		(fp_line
			(start -0.67945 0.3048)
			(end -0.67945 -0.305054)
			(stroke
				(width 0.1)
				(type default)
			)
			(layer "F.Fab")
		)
		(fp_line
			(start -0.67945 -0.305054)
			(end -0.12065 -0.305054)
			(stroke
				(width 0.1)
				(type default)
			)
			(layer "F.Fab")
		)
		(pad "1" smd circle
			(at -0.40005 0 180)
			(size 0 0)
			(layers "F.Cu" "F.Mask" "F.Paste")
			(net "PVCCINFAON_CPU1_VCC")
		)
		(pad "2" smd circle
			(at 0.40005 0 180)
			(size 0 0)
			(layers "F.Cu" "F.Mask" "F.Paste")
			(net "GND")
		)
	)
)
